(kicad_pcb
	(version 20260206)
	(generator "pcbnew")
	(generator_version "10.0")
	(general
		(thickness 1.6)
		(legacy_teardrops no)
	)
	(paper "A4")
	(title_block
		(title "01162023_DA0F0TEBIF0_F0T_Expander_BD_F_brd_V02_OCP.brd")
		(comment 1 "Grand Teton / footprints 1629-1635 of 9728")
	)
	(layers
		(0 "F.Cu" signal "TOP")
		(4 "In1.Cu" signal "GND")
		(6 "In2.Cu" signal "VCC")
		(8 "In3.Cu" signal "VCC1")
		(10 "In4.Cu" signal "GND1")
		(12 "In5.Cu" signal "IN1")
		(14 "In6.Cu" signal "GND2")
		(16 "In7.Cu" signal "IN2")
		(18 "In8.Cu" signal "GND3")
		(20 "In9.Cu" signal "IN3")
		(22 "In10.Cu" signal "GND4")
		(24 "In11.Cu" signal "IN4")
		(26 "In12.Cu" signal "GND5")
		(28 "In13.Cu" signal "IN5")
		(30 "In14.Cu" signal "GND6")
		(32 "In15.Cu" signal "IN6")
		(34 "In16.Cu" signal "GND7")
		(2 "B.Cu" signal "BOTTOM")
		(9 "F.Adhes" user "F.Adhesive")
		(11 "B.Adhes" user "B.Adhesive")
		(13 "F.Paste" user "Package Geometry/Pastemask Top")
		(15 "B.Paste" user "Package Geometry/Pastemask Bottom")
		(5 "F.SilkS" user "Ref Des/Silkscreen Top")
		(7 "B.SilkS" user "Ref Des/Silkscreen Bottom")
		(1 "F.Mask" user "Board Geometry/Soldermask Top")
		(3 "B.Mask" user "Board Geometry/Soldermask Bottom")
		(17 "Dwgs.User" user "User.Drawings")
		(19 "Cmts.User" user "User.Comments")
		(21 "Eco1.User" user "User.Eco1")
		(23 "Eco2.User" user "User.Eco2")
		(25 "Edge.Cuts" user "Board Geometry/Outline")
		(27 "Margin" user)
		(31 "F.CrtYd" user "Package Geometry/Place Bound Top")
		(29 "B.CrtYd" user "Package Geometry/Place Bound Bottom")
		(35 "F.Fab" user "Ref Des/Assembly Top")
		(33 "B.Fab" user "Ref Des/Assembly Bottom")
	)
	(footprint ""
		(layer "F.Cu")
		(at 394.973048 -22.867366 90)
		(property "Reference" "C3963"
			(at 0 0 90)
			(layer "F.SilkS")
			(hide yes)
			(effects
				(font
					(size 1.27 1.27)
				)
			)
		)
		(property "Value" ""
			(at 0 0 90)
			(layer "F.Fab")
			(effects
				(font
					(size 1.27 1.27)
				)
			)
		)
		(duplicate_pad_numbers_are_jumpers no)
		(fp_line
			(start 0.7874 -0.4064)
			(end 0.7874 0.4064)
			(stroke
				(width 0.1524)
				(type default)
			)
			(layer "F.SilkS")
		)
		(fp_line
			(start -0.7874 -0.4064)
			(end 0.7874 -0.4064)
			(stroke
				(width 0.1524)
				(type default)
			)
			(layer "F.SilkS")
		)
		(fp_line
			(start 0.7874 0.4064)
			(end -0.7874 0.4064)
			(stroke
				(width 0.1524)
				(type default)
			)
			(layer "F.SilkS")
		)
		(fp_line
			(start -0.7874 0.4064)
			(end -0.7874 -0.4064)
			(stroke
				(width 0.1524)
				(type default)
			)
			(layer "F.SilkS")
		)
		(fp_line
			(start -0.12065 -0.305054)
			(end -0.12065 -0.2794)
			(stroke
				(width 0.1)
				(type default)
			)
			(layer "F.Fab")
		)
		(fp_line
			(start -0.67945 -0.305054)
			(end -0.12065 -0.305054)
			(stroke
				(width 0.1)
				(type default)
			)
			(layer "F.Fab")
		)
		(fp_line
			(start 0.67945 -0.3048)
			(end 0.67945 0.3048)
			(stroke
				(width 0.1)
				(type default)
			)
			(layer "F.Fab")
		)
		(fp_line
			(start 0.12065 -0.3048)
			(end 0.67945 -0.3048)
			(stroke
				(width 0.1)
				(type default)
			)
			(layer "F.Fab")
		)
		(fp_line
			(start 0.12065 -0.2794)
			(end 0.12065 -0.3048)
			(stroke
				(width 0.1)
				(type default)
			)
			(layer "F.Fab")
		)
		(fp_line
			(start -0.12065 -0.2794)
			(end 0.12065 -0.2794)
			(stroke
				(width 0.1)
				(type default)
			)
			(layer "F.Fab")
		)
		(fp_line
			(start 0.120396 0.2794)
			(end -0.12065 0.2794)
			(stroke
				(width 0.1)
				(type default)
			)
			(layer "F.Fab")
		)
		(fp_line
			(start -0.12065 0.2794)
			(end -0.12065 0.3048)
			(stroke
				(width 0.1)
				(type default)
			)
			(layer "F.Fab")
		)
		(fp_line
			(start 0.67945 0.3048)
			(end 0.120396 0.3048)
			(stroke
				(width 0.1)
				(type default)
			)
			(layer "F.Fab")
		)
		(fp_line
			(start 0.120396 0.3048)
			(end 0.120396 0.2794)
			(stroke
				(width 0.1)
				(type default)
			)
			(layer "F.Fab")
		)
		(fp_line
			(start -0.12065 0.3048)
			(end -0.67945 0.3048)
			(stroke
				(width 0.1)
				(type default)
			)
			(layer "F.Fab")
		)
		(fp_line
			(start -0.67945 0.3048)
			(end -0.67945 -0.305054)
			(stroke
				(width 0.1)
				(type default)
			)
			(layer "F.Fab")
		)
		(pad "1" smd circle
			(at -0.40005 0 90)
			(size 0 0)
			(layers "F.Cu" "F.Mask" "F.Paste")
			(net "P12V_SSD13")
		)
		(pad "2" smd circle
			(at 0.40005 0 90)
			(size 0 0)
			(layers "F.Cu" "F.Mask" "F.Paste")
			(net "GND")
		)
	)
	(footprint ""
		(layer "F.Cu")
		(at 237.903512 -231.416606 90)
		(property "Reference" "R4519"
			(at 0 0 90)
			(layer "F.SilkS")
			(hide yes)
			(effects
				(font
					(size 1.27 1.27)
				)
			)
		)
		(property "Value" ""
			(at 0 0 90)
			(layer "F.Fab")
			(effects
				(font
					(size 1.27 1.27)
				)
			)
		)
		(duplicate_pad_numbers_are_jumpers no)
		(fp_line
			(start 0.7874 -0.4064)
			(end 0.7874 0.4064)
			(stroke
				(width 0.1524)
				(type default)
			)
			(layer "F.SilkS")
		)
		(fp_line
			(start -0.7874 -0.4064)
			(end 0.7874 -0.4064)
			(stroke
				(width 0.1524)
				(type default)
			)
			(layer "F.SilkS")
		)
		(fp_line
			(start 0.7874 0.4064)
			(end -0.7874 0.4064)
			(stroke
				(width 0.1524)
				(type default)
			)
			(layer "F.SilkS")
		)
		(fp_line
			(start -0.7874 0.4064)
			(end -0.7874 -0.4064)
			(stroke
				(width 0.1524)
				(type default)
			)
			(layer "F.SilkS")
		)
		(fp_line
			(start -0.12065 -0.305054)
			(end -0.12065 -0.2794)
			(stroke
				(width 0.1)
				(type default)
			)
			(layer "F.Fab")
		)
		(fp_line
			(start -0.67945 -0.305054)
			(end -0.12065 -0.305054)
			(stroke
				(width 0.1)
				(type default)
			)
			(layer "F.Fab")
		)
		(fp_line
			(start 0.67945 -0.3048)
			(end 0.67945 0.3048)
			(stroke
				(width 0.1)
				(type default)
			)
			(layer "F.Fab")
		)
		(fp_line
			(start 0.12065 -0.3048)
			(end 0.67945 -0.3048)
			(stroke
				(width 0.1)
				(type default)
			)
			(layer "F.Fab")
		)
		(fp_line
			(start 0.12065 -0.2794)
			(end 0.12065 -0.3048)
			(stroke
				(width 0.1)
				(type default)
			)
			(layer "F.Fab")
		)
		(fp_line
			(start -0.12065 -0.2794)
			(end 0.12065 -0.2794)
			(stroke
				(width 0.1)
				(type default)
			)
			(layer "F.Fab")
		)
		(fp_line
			(start 0.120396 0.2794)
			(end -0.12065 0.2794)
			(stroke
				(width 0.1)
				(type default)
			)
			(layer "F.Fab")
		)
		(fp_line
			(start -0.12065 0.2794)
			(end -0.12065 0.3048)
			(stroke
				(width 0.1)
				(type default)
			)
			(layer "F.Fab")
		)
		(fp_line
			(start 0.67945 0.3048)
			(end 0.120396 0.3048)
			(stroke
				(width 0.1)
				(type default)
			)
			(layer "F.Fab")
		)
		(fp_line
			(start 0.120396 0.3048)
			(end 0.120396 0.2794)
			(stroke
				(width 0.1)
				(type default)
			)
			(layer "F.Fab")
		)
		(fp_line
			(start -0.12065 0.3048)
			(end -0.67945 0.3048)
			(stroke
				(width 0.1)
				(type default)
			)
			(layer "F.Fab")
		)
		(fp_line
			(start -0.67945 0.3048)
			(end -0.67945 -0.305054)
			(stroke
				(width 0.1)
				(type default)
			)
			(layer "F.Fab")
		)
		(pad "1" smd circle
			(at -0.40005 0 90)
			(size 0 0)
			(layers "F.Cu" "F.Mask" "F.Paste")
			(net "SSD5_PWRDIS_BIC")
		)
		(pad "2" smd circle
			(at 0.40005 0 90)
			(size 0 0)
			(layers "F.Cu" "F.Mask" "F.Paste")
			(net "SSD5_PWRDIS_BIC_R")
		)
	)
	(footprint ""
		(layer "F.Cu")
		(at 317.30315 -59.571636 90)
		(property "Reference" "PR286"
			(at 0 0 90)
			(layer "F.SilkS")
			(hide yes)
			(effects
				(font
					(size 1.27 1.27)
				)
			)
		)
		(property "Value" ""
			(at 0 0 90)
			(layer "F.Fab")
			(effects
				(font
					(size 1.27 1.27)
				)
			)
		)
		(duplicate_pad_numbers_are_jumpers no)
		(fp_line
			(start 0.7874 -0.4064)
			(end 0.7874 0.4064)
			(stroke
				(width 0.1524)
				(type default)
			)
			(layer "F.SilkS")
		)
		(fp_line
			(start -0.7874 -0.4064)
			(end 0.7874 -0.4064)
			(stroke
				(width 0.1524)
				(type default)
			)
			(layer "F.SilkS")
		)
		(fp_line
			(start 0.7874 0.4064)
			(end -0.7874 0.4064)
			(stroke
				(width 0.1524)
				(type default)
			)
			(layer "F.SilkS")
		)
		(fp_line
			(start -0.7874 0.4064)
			(end -0.7874 -0.4064)
			(stroke
				(width 0.1524)
				(type default)
			)
			(layer "F.SilkS")
		)
		(fp_line
			(start -0.12065 -0.305054)
			(end -0.12065 -0.2794)
			(stroke
				(width 0.1)
				(type default)
			)
			(layer "F.Fab")
		)
		(fp_line
			(start -0.67945 -0.305054)
			(end -0.12065 -0.305054)
			(stroke
				(width 0.1)
				(type default)
			)
			(layer "F.Fab")
		)
		(fp_line
			(start 0.67945 -0.3048)
			(end 0.67945 0.3048)
			(stroke
				(width 0.1)
				(type default)
			)
			(layer "F.Fab")
		)
		(fp_line
			(start 0.12065 -0.3048)
			(end 0.67945 -0.3048)
			(stroke
				(width 0.1)
				(type default)
			)
			(layer "F.Fab")
		)
		(fp_line
			(start 0.12065 -0.2794)
			(end 0.12065 -0.3048)
			(stroke
				(width 0.1)
				(type default)
			)
			(layer "F.Fab")
		)
		(fp_line
			(start -0.12065 -0.2794)
			(end 0.12065 -0.2794)
			(stroke
				(width 0.1)
				(type default)
			)
			(layer "F.Fab")
		)
		(fp_line
			(start 0.120396 0.2794)
			(end -0.12065 0.2794)
			(stroke
				(width 0.1)
				(type default)
			)
			(layer "F.Fab")
		)
		(fp_line
			(start -0.12065 0.2794)
			(end -0.12065 0.3048)
			(stroke
				(width 0.1)
				(type default)
			)
			(layer "F.Fab")
		)
		(fp_line
			(start 0.67945 0.3048)
			(end 0.120396 0.3048)
			(stroke
				(width 0.1)
				(type default)
			)
			(layer "F.Fab")
		)
		(fp_line
			(start 0.120396 0.3048)
			(end 0.120396 0.2794)
			(stroke
				(width 0.1)
				(type default)
			)
			(layer "F.Fab")
		)
		(fp_line
			(start -0.12065 0.3048)
			(end -0.67945 0.3048)
			(stroke
				(width 0.1)
				(type default)
			)
			(layer "F.Fab")
		)
		(fp_line
			(start -0.67945 0.3048)
			(end -0.67945 -0.305054)
			(stroke
				(width 0.1)
				(type default)
			)
			(layer "F.Fab")
		)
		(pad "1" smd circle
			(at -0.40005 0 90)
			(size 0 0)
			(layers "F.Cu" "F.Mask" "F.Paste")
			(net "P3V3_SSD11_OCP")
		)
		(pad "2" smd circle
			(at 0.40005 0 90)
			(size 0 0)
			(layers "F.Cu" "F.Mask" "F.Paste")
			(net "GND")
		)
	)
	(footprint ""
		(layer "F.Cu")
		(at 356.420674 -26.666444 -90)
		(property "Reference" "R4077"
			(at 0 0 270)
			(layer "F.SilkS")
			(hide yes)
			(effects
				(font
					(size 1.27 1.27)
				)
			)
		)
		(property "Value" ""
			(at 0 0 270)
			(layer "F.Fab")
			(effects
				(font
					(size 1.27 1.27)
				)
			)
		)
		(duplicate_pad_numbers_are_jumpers no)
		(fp_line
			(start -0.7874 0.4064)
			(end -0.7874 -0.4064)
			(stroke
				(width 0.1524)
				(type default)
			)
			(layer "F.SilkS")
		)
		(fp_line
			(start 0.7874 0.4064)
			(end -0.7874 0.4064)
			(stroke
				(width 0.1524)
				(type default)
			)
			(layer "F.SilkS")
		)
		(fp_line
			(start -0.7874 -0.4064)
			(end 0.7874 -0.4064)
			(stroke
				(width 0.1524)
				(type default)
			)
			(layer "F.SilkS")
		)
		(fp_line
			(start 0.7874 -0.4064)
			(end 0.7874 0.4064)
			(stroke
				(width 0.1524)
				(type default)
			)
			(layer "F.SilkS")
		)
		(fp_line
			(start -0.67945 0.3048)
			(end -0.67945 -0.305054)
			(stroke
				(width 0.1)
				(type default)
			)
			(layer "F.Fab")
		)
		(fp_line
			(start -0.12065 0.3048)
			(end -0.67945 0.3048)
			(stroke
				(width 0.1)
				(type default)
			)
			(layer "F.Fab")
		)
		(fp_line
			(start 0.120396 0.3048)
			(end 0.120396 0.2794)
			(stroke
				(width 0.1)
				(type default)
			)
			(layer "F.Fab")
		)
		(fp_line
			(start 0.67945 0.3048)
			(end 0.120396 0.3048)
			(stroke
				(width 0.1)
				(type default)
			)
			(layer "F.Fab")
		)
		(fp_line
			(start -0.12065 0.2794)
			(end -0.12065 0.3048)
			(stroke
				(width 0.1)
				(type default)
			)
			(layer "F.Fab")
		)
		(fp_line
			(start 0.120396 0.2794)
			(end -0.12065 0.2794)
			(stroke
				(width 0.1)
				(type default)
			)
			(layer "F.Fab")
		)
		(fp_line
			(start -0.12065 -0.2794)
			(end 0.12065 -0.2794)
			(stroke
				(width 0.1)
				(type default)
			)
			(layer "F.Fab")
		)
		(fp_line
			(start 0.12065 -0.2794)
			(end 0.12065 -0.3048)
			(stroke
				(width 0.1)
				(type default)
			)
			(layer "F.Fab")
		)
		(fp_line
			(start 0.12065 -0.3048)
			(end 0.67945 -0.3048)
			(stroke
				(width 0.1)
				(type default)
			)
			(layer "F.Fab")
		)
		(fp_line
			(start 0.67945 -0.3048)
			(end 0.67945 0.3048)
			(stroke
				(width 0.1)
				(type default)
			)
			(layer "F.Fab")
		)
		(fp_line
			(start -0.67945 -0.305054)
			(end -0.12065 -0.305054)
			(stroke
				(width 0.1)
				(type default)
			)
			(layer "F.Fab")
		)
		(fp_line
			(start -0.12065 -0.305054)
			(end -0.12065 -0.2794)
			(stroke
				(width 0.1)
				(type default)
			)
			(layer "F.Fab")
		)
		(pad "1" smd circle
			(at -0.40005 0 270)
			(size 0 0)
			(layers "F.Cu" "F.Mask" "F.Paste")
			(net "PRSNT_SSD12_R_N")
		)
		(pad "2" smd circle
			(at 0.40005 0 270)
			(size 0 0)
			(layers "F.Cu" "F.Mask" "F.Paste")
			(net "PRSNT_SSD12_N")
		)
	)
	(footprint ""
		(layer "F.Cu")
		(at 395.830552 -66.32194 -90)
		(property "Reference" "PC887"
			(at 0 0 270)
			(layer "F.SilkS")
			(hide yes)
			(effects
				(font
					(size 1.27 1.27)
				)
			)
		)
		(property "Value" ""
			(at 0 0 270)
			(layer "F.Fab")
			(effects
				(font
					(size 1.27 1.27)
				)
			)
		)
		(duplicate_pad_numbers_are_jumpers no)
		(fp_line
			(start -0.7874 0.4064)
			(end -0.7874 -0.4064)
			(stroke
				(width 0.1524)
				(type default)
			)
			(layer "F.SilkS")
		)
		(fp_line
			(start 0.7874 0.4064)
			(end -0.7874 0.4064)
			(stroke
				(width 0.1524)
				(type default)
			)
			(layer "F.SilkS")
		)
		(fp_line
			(start -0.7874 -0.4064)
			(end 0.7874 -0.4064)
			(stroke
				(width 0.1524)
				(type default)
			)
			(layer "F.SilkS")
		)
		(fp_line
			(start 0.7874 -0.4064)
			(end 0.7874 0.4064)
			(stroke
				(width 0.1524)
				(type default)
			)
			(layer "F.SilkS")
		)
		(fp_line
			(start -0.67945 0.3048)
			(end -0.67945 -0.305054)
			(stroke
				(width 0.1)
				(type default)
			)
			(layer "F.Fab")
		)
		(fp_line
			(start -0.12065 0.3048)
			(end -0.67945 0.3048)
			(stroke
				(width 0.1)
				(type default)
			)
			(layer "F.Fab")
		)
		(fp_line
			(start 0.120396 0.3048)
			(end 0.120396 0.2794)
			(stroke
				(width 0.1)
				(type default)
			)
			(layer "F.Fab")
		)
		(fp_line
			(start 0.67945 0.3048)
			(end 0.120396 0.3048)
			(stroke
				(width 0.1)
				(type default)
			)
			(layer "F.Fab")
		)
		(fp_line
			(start -0.12065 0.2794)
			(end -0.12065 0.3048)
			(stroke
				(width 0.1)
				(type default)
			)
			(layer "F.Fab")
		)
		(fp_line
			(start 0.120396 0.2794)
			(end -0.12065 0.2794)
			(stroke
				(width 0.1)
				(type default)
			)
			(layer "F.Fab")
		)
		(fp_line
			(start -0.12065 -0.2794)
			(end 0.12065 -0.2794)
			(stroke
				(width 0.1)
				(type default)
			)
			(layer "F.Fab")
		)
		(fp_line
			(start 0.12065 -0.2794)
			(end 0.12065 -0.3048)
			(stroke
				(width 0.1)
				(type default)
			)
			(layer "F.Fab")
		)
		(fp_line
			(start 0.12065 -0.3048)
			(end 0.67945 -0.3048)
			(stroke
				(width 0.1)
				(type default)
			)
			(layer "F.Fab")
		)
		(fp_line
			(start 0.67945 -0.3048)
			(end 0.67945 0.3048)
			(stroke
				(width 0.1)
				(type default)
			)
			(layer "F.Fab")
		)
		(fp_line
			(start -0.67945 -0.305054)
			(end -0.12065 -0.305054)
			(stroke
				(width 0.1)
				(type default)
			)
			(layer "F.Fab")
		)
		(fp_line
			(start -0.12065 -0.305054)
			(end -0.12065 -0.2794)
			(stroke
				(width 0.1)
				(type default)
			)
			(layer "F.Fab")
		)
		(pad "1" smd circle
			(at -0.40005 0 270)
			(size 0 0)
			(layers "F.Cu" "F.Mask" "F.Paste")
			(net "P12V_SSD13_CO_DV_DT")
		)
		(pad "2" smd circle
			(at 0.40005 0 270)
			(size 0 0)
			(layers "F.Cu" "F.Mask" "F.Paste")
			(net "GND")
		)
	)
	(footprint ""
		(layer "F.Cu")
		(at 266.378944 -59.577986 -90)
		(property "Reference" "R896"
			(at 0 0 270)
			(layer "F.SilkS")
			(hide yes)
			(effects
				(font
					(size 1.27 1.27)
				)
			)
		)
		(property "Value" ""
			(at 0 0 270)
			(layer "F.Fab")
			(effects
				(font
					(size 1.27 1.27)
				)
			)
		)
		(duplicate_pad_numbers_are_jumpers no)
		(fp_line
			(start -0.7874 0.4064)
			(end -0.7874 -0.4064)
			(stroke
				(width 0.1524)
				(type default)
			)
			(layer "F.SilkS")
		)
		(fp_line
			(start 0.7874 0.4064)
			(end -0.7874 0.4064)
			(stroke
				(width 0.1524)
				(type default)
			)
			(layer "F.SilkS")
		)
		(fp_line
			(start -0.7874 -0.4064)
			(end 0.7874 -0.4064)
			(stroke
				(width 0.1524)
				(type default)
			)
			(layer "F.SilkS")
		)
		(fp_line
			(start 0.7874 -0.4064)
			(end 0.7874 0.4064)
			(stroke
				(width 0.1524)
				(type default)
			)
			(layer "F.SilkS")
		)
		(fp_line
			(start -0.67945 0.3048)
			(end -0.67945 -0.305054)
			(stroke
				(width 0.1)
				(type default)
			)
			(layer "F.Fab")
		)
		(fp_line
			(start -0.12065 0.3048)
			(end -0.67945 0.3048)
			(stroke
				(width 0.1)
				(type default)
			)
			(layer "F.Fab")
		)
		(fp_line
			(start 0.120396 0.3048)
			(end 0.120396 0.2794)
			(stroke
				(width 0.1)
				(type default)
			)
			(layer "F.Fab")
		)
		(fp_line
			(start 0.67945 0.3048)
			(end 0.120396 0.3048)
			(stroke
				(width 0.1)
				(type default)
			)
			(layer "F.Fab")
		)
		(fp_line
			(start -0.12065 0.2794)
			(end -0.12065 0.3048)
			(stroke
				(width 0.1)
				(type default)
			)
			(layer "F.Fab")
		)
		(fp_line
			(start 0.120396 0.2794)
			(end -0.12065 0.2794)
			(stroke
				(width 0.1)
				(type default)
			)
			(layer "F.Fab")
		)
		(fp_line
			(start -0.12065 -0.2794)
			(end 0.12065 -0.2794)
			(stroke
				(width 0.1)
				(type default)
			)
			(layer "F.Fab")
		)
		(fp_line
			(start 0.12065 -0.2794)
			(end 0.12065 -0.3048)
			(stroke
				(width 0.1)
				(type default)
			)
			(layer "F.Fab")
		)
		(fp_line
			(start 0.12065 -0.3048)
			(end 0.67945 -0.3048)
			(stroke
				(width 0.1)
				(type default)
			)
			(layer "F.Fab")
		)
		(fp_line
			(start 0.67945 -0.3048)
			(end 0.67945 0.3048)
			(stroke
				(width 0.1)
				(type default)
			)
			(layer "F.Fab")
		)
		(fp_line
			(start -0.67945 -0.305054)
			(end -0.12065 -0.305054)
			(stroke
				(width 0.1)
				(type default)
			)
			(layer "F.Fab")
		)
		(fp_line
			(start -0.12065 -0.305054)
			(end -0.12065 -0.2794)
			(stroke
				(width 0.1)
				(type default)
			)
			(layer "F.Fab")
		)
		(pad "1" smd circle
			(at -0.40005 0 270)
			(size 0 0)
			(layers "F.Cu" "F.Mask" "F.Paste")
			(net "P3V3_SSD9")
		)
		(pad "2" smd circle
			(at 0.40005 0 270)
			(size 0 0)
			(layers "F.Cu" "F.Mask" "F.Paste")
			(net "PWRGD_P3V3_SSD9")
		)
	)
	(footprint ""
		(layer "F.Cu")
		(at 344.481404 -350.098614 90)
		(property "Reference" "C520"
			(at 0 0 90)
			(layer "F.SilkS")
			(hide yes)
			(effects
				(font
					(size 1.27 1.27)
				)
			)
		)
		(property "Value" ""
			(at 0 0 90)
			(layer "F.Fab")
			(effects
				(font
					(size 1.27 1.27)
				)
			)
		)
		(duplicate_pad_numbers_are_jumpers no)
		(fp_line
			(start 0.299974 -0.150114)
			(end 0.299974 0.150114)
			(stroke
				(width 0.1)
				(type default)
			)
			(layer "F.Fab")
		)
		(fp_line
			(start -0.299974 -0.150114)
			(end 0.299974 -0.150114)
			(stroke
				(width 0.1)
				(type default)
			)
			(layer "F.Fab")
		)
		(fp_line
			(start 0.299974 0.150114)
			(end -0.299974 0.150114)
			(stroke
				(width 0.1)
				(type default)
			)
			(layer "F.Fab")
		)
		(fp_line
			(start -0.299974 0.150114)
			(end -0.299974 -0.150114)
			(stroke
				(width 0.1)
				(type default)
			)
			(layer "F.Fab")
		)
		(pad "1" smd rect
			(at -0.2667 0 90)
			(size 0.3048 0.381)
			(layers "F.Cu" "F.Mask" "F.Paste")
			(net "P5E_PEX2_STN5_TX_DN<95>")
		)
		(pad "2" smd rect
			(at 0.2667 0 90)
			(size 0.3048 0.381)
			(layers "F.Cu" "F.Mask" "F.Paste")
			(net "P5E_PEX2_STN5_TX_C_DN<95>")
		)
	)
)
